(kicad_pcb
	(version 20260206)
	(generator "pcbnew")
	(generator_version "10.0")
	(general
		(thickness 1.6)
		(legacy_teardrops no)
	)
	(paper "A4")
	(title_block
		(title "pdpb — Lightning_PDPB_BRD.brd")
		(comment 1 "Lightning (Wiwynn / Facebook NVMe JBOF) / footprints 44-50 of 1140")
	)
	(layers
		(0 "F.Cu" signal "TOP")
		(4 "In1.Cu" signal "L2GND")
		(6 "In2.Cu" signal "L3")
		(8 "In3.Cu" signal "L4VCC")
		(10 "In4.Cu" signal "L5VCC")
		(12 "In5.Cu" signal "L6")
		(14 "In6.Cu" signal "L7GND")
		(2 "B.Cu" signal "BOTTOM")
		(9 "F.Adhes" user "F.Adhesive")
		(11 "B.Adhes" user "B.Adhesive")
		(13 "F.Paste" user "Package Geometry/Pastemask Top")
		(15 "B.Paste" user "Package Geometry/Pastemask Bottom")
		(5 "F.SilkS" user "Ref Des/Silkscreen Top")
		(7 "B.SilkS" user "Ref Des/Silkscreen Bottom")
		(1 "F.Mask" user "Board Geometry/Soldermask Top")
		(3 "B.Mask" user "Board Geometry/Soldermask Bottom")
		(17 "Dwgs.User" user "User.Drawings")
		(19 "Cmts.User" user "User.Comments")
		(21 "Eco1.User" user "User.Eco1")
		(23 "Eco2.User" user "User.Eco2")
		(25 "Edge.Cuts" user "Board Geometry/Outline")
		(27 "Margin" user)
		(31 "F.CrtYd" user "Package Geometry/Place Bound Top")
		(29 "B.CrtYd" user "Package Geometry/Place Bound Bottom")
		(35 "F.Fab" user "Ref Des/Assembly Top")
		(33 "B.Fab" user "Ref Des/Assembly Bottom")
	)
	(footprint ""
		(layer "F.Cu")
		(at 8.7122 -464.1342 90)
		(property "Reference" "PC1164"
			(at 0 0 90)
			(layer "F.SilkS")
			(hide yes)
			(effects
				(font
					(size 1.27 1.27)
				)
			)
		)
		(property "Value" "SCD1U50V3KX-GP"
			(at 0 -2.8194 90)
			(unlocked yes)
			(layer "F.Fab")
			(hide yes)
			(effects
				(font
					(size 1.016 1.016)
					(thickness 0.1524)
				)
			)
		)
		(property "Device Type" "C603H36"
			(at 0 -4.3434 90)
			(unlocked yes)
			(layer "F.Fab")
			(hide yes)
			(effects
				(font
					(size 1.016 1.016)
					(thickness 0.1524)
				)
			)
		)
		(duplicate_pad_numbers_are_jumpers no)
		(fp_line
			(start 0.508 0)
			(end -0.508 0)
			(stroke
				(width 0.2032)
				(type default)
			)
			(layer "F.SilkS")
		)
		(fp_rect
			(start -0.5842 1.3335)
			(end 0.5842 -1.3335)
			(stroke
				(width 0)
				(type default)
			)
			(fill no)
			(layer "F.CrtYd")
		)
		(fp_rect
			(start -0.5842 1.3335)
			(end 0.5842 -1.3335)
			(stroke
				(width 0)
				(type default)
			)
			(fill no)
			(layer "F.Fab")
		)
		(pad "1" smd custom
			(at 0 -0.762 90)
			(size 0.2159 0.2159)
			(layers "F.Cu" "F.Mask" "F.Paste")
			(net "P12V")
			(options
				(clearance outline)
				(anchor circle)
			)
			(primitives
				(gr_poly
					(pts
						(arc
							(start -0.3302 -0.4318)
							(mid -0.402042 -0.402042)
							(end -0.4318 -0.3302)
						)
						(arc
							(start -0.4318 0.3302)
							(mid -0.402042 0.402042)
							(end -0.3302 0.4318)
						)
						(arc
							(start 0.3302 0.4318)
							(mid 0.402042 0.402042)
							(end 0.4318 0.3302)
						)
						(arc
							(start 0.4318 -0.3302)
							(mid 0.402042 -0.402042)
							(end 0.3302 -0.4318)
						)
					)
					(width 0)
					(fill yes)
				)
			)
		)
		(pad "2" smd custom
			(at 0 0.762 90)
			(size 0.2159 0.2159)
			(layers "F.Cu" "F.Mask" "F.Paste")
			(net "GND")
			(options
				(clearance outline)
				(anchor circle)
			)
			(primitives
				(gr_poly
					(pts
						(arc
							(start -0.3302 -0.4318)
							(mid -0.402042 -0.402042)
							(end -0.4318 -0.3302)
						)
						(arc
							(start -0.4318 0.3302)
							(mid -0.402042 0.402042)
							(end -0.3302 0.4318)
						)
						(arc
							(start 0.3302 0.4318)
							(mid 0.402042 0.402042)
							(end 0.4318 0.3302)
						)
						(arc
							(start 0.4318 -0.3302)
							(mid 0.402042 -0.402042)
							(end 0.3302 -0.4318)
						)
					)
					(width 0)
					(fill yes)
				)
			)
		)
	)
	(footprint ""
		(layer "F.Cu")
		(at 24.892 -365.887 90)
		(property "Reference" "Q84"
			(at 0 0 90)
			(layer "F.SilkS")
			(hide yes)
			(effects
				(font
					(size 1.27 1.27)
				)
			)
		)
		(property "Value" "2N7002A-7-GP"
			(at 0.127 -8.9662 90)
			(unlocked yes)
			(layer "F.Fab")
			(hide yes)
			(effects
				(font
					(size 1.016 1.016)
					(thickness 0.1524)
				)
			)
		)
		(property "Device Type" "SOT23DGS2D4H48"
			(at 0.127 -10.4902 90)
			(unlocked yes)
			(layer "F.Fab")
			(hide yes)
			(effects
				(font
					(size 1.016 1.016)
					(thickness 0.1524)
				)
			)
		)
		(duplicate_pad_numbers_are_jumpers no)
		(fp_line
			(start 1.651 -1.778)
			(end -1.651 -1.778)
			(stroke
				(width 0.1524)
				(type default)
			)
			(layer "F.SilkS")
		)
		(fp_line
			(start -1.651 -1.778)
			(end -1.651 1.778)
			(stroke
				(width 0.1524)
				(type default)
			)
			(layer "F.SilkS")
		)
		(fp_line
			(start 1.651 1.778)
			(end 1.651 -1.778)
			(stroke
				(width 0.1524)
				(type default)
			)
			(layer "F.SilkS")
		)
		(fp_line
			(start -1.651 1.778)
			(end 1.651 1.778)
			(stroke
				(width 0.1524)
				(type default)
			)
			(layer "F.SilkS")
		)
		(fp_poly
			(pts
				(xy -1.778 1.8796) (xy -1.778 -1.8796) (xy 1.778 -1.8796) (xy 1.778 1.8796)
			)
			(stroke
				(width 0)
				(type default)
			)
			(fill no)
			(layer "F.CrtYd")
		)
		(fp_poly
			(pts
				(xy -1.778 1.8796) (xy -1.778 -1.8796) (xy 1.778 -1.8796) (xy 1.778 1.8796)
			)
			(stroke
				(width 0)
				(type default)
			)
			(fill no)
			(layer "F.Fab")
		)
		(pad "D" smd custom
			(at 0 -0.9525 90)
			(size 0.1905 0.1905)
			(layers "F.Cu" "F.Mask" "F.Paste")
			(net "SSD11_CLK0_OE_MOS_N")
			(options
				(clearance outline)
				(anchor circle)
			)
			(primitives
				(gr_poly
					(pts
						(arc
							(start -0.1778 0.5715)
							(mid -0.321484 0.511984)
							(end -0.381 0.3683)
						)
						(arc
							(start -0.381 -0.3683)
							(mid -0.321484 -0.511984)
							(end -0.1778 -0.5715)
						)
						(arc
							(start 0.1778 -0.5715)
							(mid 0.321484 -0.511984)
							(end 0.381 -0.3683)
						)
						(arc
							(start 0.381 0.3683)
							(mid 0.321484 0.511984)
							(end 0.1778 0.5715)
						)
					)
					(width 0)
					(fill yes)
				)
			)
		)
		(pad "G" smd custom
			(at -0.98425 0.9525 90)
			(size 0.1905 0.1905)
			(layers "F.Cu" "F.Mask" "F.Paste")
			(net "SSD11_CLK0_OE_R_N")
			(options
				(clearance outline)
				(anchor circle)
			)
			(primitives
				(gr_poly
					(pts
						(arc
							(start -0.1778 0.5715)
							(mid -0.321484 0.511984)
							(end -0.381 0.3683)
						)
						(arc
							(start -0.381 -0.3683)
							(mid -0.321484 -0.511984)
							(end -0.1778 -0.5715)
						)
						(arc
							(start 0.1778 -0.5715)
							(mid 0.321484 -0.511984)
							(end 0.381 -0.3683)
						)
						(arc
							(start 0.381 0.3683)
							(mid 0.321484 0.511984)
							(end 0.1778 0.5715)
						)
					)
					(width 0)
					(fill yes)
				)
			)
		)
		(pad "S" smd custom
			(at 0.98425 0.9525 90)
			(size 0.1905 0.1905)
			(layers "F.Cu" "F.Mask" "F.Paste")
			(net "GND")
			(options
				(clearance outline)
				(anchor circle)
			)
			(primitives
				(gr_poly
					(pts
						(arc
							(start -0.1778 0.5715)
							(mid -0.321484 0.511984)
							(end -0.381 0.3683)
						)
						(arc
							(start -0.381 -0.3683)
							(mid -0.321484 -0.511984)
							(end -0.1778 -0.5715)
						)
						(arc
							(start 0.1778 -0.5715)
							(mid 0.321484 -0.511984)
							(end 0.381 -0.3683)
						)
						(arc
							(start 0.381 0.3683)
							(mid 0.321484 0.511984)
							(end 0.1778 0.5715)
						)
					)
					(width 0)
					(fill yes)
				)
			)
		)
	)
	(footprint ""
		(layer "F.Cu")
		(at 18.50009 -155.90012)
		(property "Reference" "LED13"
			(at 0 0 0)
			(layer "F.SilkS")
			(hide yes)
			(effects
				(font
					(size 1.27 1.27)
				)
			)
		)
		(property "Value" "LED-RB-4-GP"
			(at 5.88899 1.80848 0)
			(unlocked yes)
			(layer "F.Fab")
			(hide yes)
			(effects
				(font
					(size 1.016 1.016)
					(thickness 0.1524)
				)
			)
		)
		(property "Device Type" "LED1613-4PH20"
			(at 5.88899 0.28448 0)
			(unlocked yes)
			(layer "F.Fab")
			(hide yes)
			(effects
				(font
					(size 1.016 1.016)
					(thickness 0.1524)
				)
			)
		)
		(duplicate_pad_numbers_are_jumpers no)
		(fp_line
			(start -1.4478 -0.9652)
			(end 1.4478 -0.9652)
			(stroke
				(width 0.1524)
				(type default)
			)
			(layer "F.SilkS")
		)
		(fp_line
			(start -1.4478 0.9652)
			(end -1.4478 -0.9652)
			(stroke
				(width 0.1524)
				(type default)
			)
			(layer "F.SilkS")
		)
		(fp_line
			(start -1.4478 0.9652)
			(end -1.4478 -0.9652)
			(stroke
				(width 0.508)
				(type default)
			)
			(layer "F.SilkS")
		)
		(fp_line
			(start 1.4478 -0.9652)
			(end 1.4478 0.9652)
			(stroke
				(width 0.1524)
				(type default)
			)
			(layer "F.SilkS")
		)
		(fp_line
			(start 1.4478 0.9652)
			(end -1.4478 0.9652)
			(stroke
				(width 0.1524)
				(type default)
			)
			(layer "F.SilkS")
		)
		(fp_rect
			(start -0.8001 0.6477)
			(end 0.8001 -0.6477)
			(stroke
				(width 0)
				(type default)
			)
			(fill no)
			(layer "F.CrtYd")
		)
		(fp_poly
			(pts
				(xy -1.7018 1.2192) (xy -1.7018 -0.06223) (xy -0.8001 -0.06223) (xy -0.8001 0.6477) (xy 0.8001 0.6477)
				(xy 0.8001 -0.6477) (xy -0.8001 -0.6477) (xy -0.8001 -0.0635) (xy -1.7018 -0.0635) (xy -1.7018 -1.2192)
				(xy 1.7018 -1.2192) (xy 1.7018 1.2192)
			)
			(stroke
				(width 0)
				(type default)
			)
			(fill no)
			(layer "F.CrtYd")
		)
		(fp_rect
			(start -1.7018 1.2192)
			(end 1.7018 -1.2192)
			(stroke
				(width 0)
				(type default)
			)
			(fill no)
			(layer "F.Fab")
		)
		(pad "1" smd rect
			(at -0.73025 0.4064)
			(size 0.9144 0.6096)
			(layers "F.Cu" "F.Mask" "F.Paste")
			(net "SSD_ACT_DR13_MOS_N")
		)
		(pad "2" smd rect
			(at -0.73025 -0.4064)
			(size 0.9144 0.6096)
			(layers "F.Cu" "F.Mask" "F.Paste")
			(net "ATTN_LED_DR13_MOS_N")
		)
		(pad "3" smd rect
			(at 0.73025 -0.4064)
			(size 0.9144 0.6096)
			(layers "F.Cu" "F.Mask" "F.Paste")
			(net "DRV_ATTN_13")
		)
		(pad "4" smd rect
			(at 0.73025 0.4064)
			(size 0.9144 0.6096)
			(layers "F.Cu" "F.Mask" "F.Paste")
			(net "DRV_ACT_13")
		)
	)
	(footprint ""
		(layer "F.Cu")
		(at 84.455 -298.323 -90)
		(property "Reference" "R9037"
			(at 0 0 270)
			(layer "F.SilkS")
			(hide yes)
			(effects
				(font
					(size 1.27 1.27)
				)
			)
		)
		(property "Value" "4K7R2F-GP"
			(at 0.064008 -3.993896 270)
			(unlocked yes)
			(layer "F.Fab")
			(hide yes)
			(effects
				(font
					(size 1.016 1.016)
					(thickness 0.1524)
				)
			)
		)
		(property "Device Type" "R402H16"
			(at 0.064008 -5.517896 270)
			(unlocked yes)
			(layer "F.Fab")
			(hide yes)
			(effects
				(font
					(size 1.016 1.016)
					(thickness 0.1524)
				)
			)
		)
		(duplicate_pad_numbers_are_jumpers no)
		(fp_line
			(start -0.508 -0.9398)
			(end -0.508 0.9398)
			(stroke
				(width 0.1524)
				(type default)
			)
			(layer "F.SilkS")
		)
		(fp_line
			(start 0.508 -0.9398)
			(end -0.508 -0.9398)
			(stroke
				(width 0.1524)
				(type default)
			)
			(layer "F.SilkS")
		)
		(fp_rect
			(start -0.508 0.9398)
			(end 0.508 -0.9398)
			(stroke
				(width 0)
				(type default)
			)
			(fill no)
			(layer "F.CrtYd")
		)
		(fp_rect
			(start -0.508 0.9398)
			(end 0.508 -0.9398)
			(stroke
				(width 0)
				(type default)
			)
			(fill no)
			(layer "F.Fab")
		)
		(pad "1" smd custom
			(at 0 -0.4445 270)
			(size 0.1397 0.1397)
			(layers "F.Cu" "F.Mask" "F.Paste")
			(net "CLK_BUF_EU2_SMB_A1_TRI")
			(options
				(clearance outline)
				(anchor circle)
			)
			(primitives
				(gr_poly
					(pts
						(arc
							(start -0.1778 -0.2794)
							(mid -0.249642 -0.249642)
							(end -0.2794 -0.1778)
						)
						(arc
							(start -0.2794 0.1778)
							(mid -0.249642 0.249642)
							(end -0.1778 0.2794)
						)
						(arc
							(start 0.1778 0.2794)
							(mid 0.249642 0.249642)
							(end 0.2794 0.1778)
						)
						(arc
							(start 0.2794 -0.1778)
							(mid 0.249642 -0.249642)
							(end 0.1778 -0.2794)
						)
					)
					(width 0)
					(fill yes)
				)
			)
		)
		(pad "2" smd custom
			(at 0 0.4445 270)
			(size 0.1397 0.1397)
			(layers "F.Cu" "F.Mask" "F.Paste")
			(net "GND")
			(options
				(clearance outline)
				(anchor circle)
			)
			(primitives
				(gr_poly
					(pts
						(arc
							(start -0.1778 -0.2794)
							(mid -0.249642 -0.249642)
							(end -0.2794 -0.1778)
						)
						(arc
							(start -0.2794 0.1778)
							(mid -0.249642 0.249642)
							(end -0.1778 0.2794)
						)
						(arc
							(start 0.1778 0.2794)
							(mid 0.249642 0.249642)
							(end 0.2794 0.1778)
						)
						(arc
							(start 0.2794 -0.1778)
							(mid 0.249642 -0.249642)
							(end 0.1778 -0.2794)
						)
					)
					(width 0)
					(fill yes)
				)
			)
		)
	)
	(footprint ""
		(layer "F.Cu")
		(at 82.931 -216.154 90)
		(property "Reference" "SR951"
			(at 0 0 90)
			(layer "F.SilkS")
			(hide yes)
			(effects
				(font
					(size 1.27 1.27)
				)
			)
		)
		(property "Value" "4K7R2F-GP"
			(at 0.064008 -3.993896 90)
			(unlocked yes)
			(layer "F.Fab")
			(hide yes)
			(effects
				(font
					(size 1.016 1.016)
					(thickness 0.1524)
				)
			)
		)
		(property "Device Type" "R402H16"
			(at 0.064008 -5.517896 90)
			(unlocked yes)
			(layer "F.Fab")
			(hide yes)
			(effects
				(font
					(size 1.016 1.016)
					(thickness 0.1524)
				)
			)
		)
		(duplicate_pad_numbers_are_jumpers no)
		(fp_line
			(start 0.508 -0.9398)
			(end -0.508 -0.9398)
			(stroke
				(width 0.1524)
				(type default)
			)
			(layer "F.SilkS")
		)
		(fp_line
			(start -0.508 -0.9398)
			(end -0.508 0.9398)
			(stroke
				(width 0.1524)
				(type default)
			)
			(layer "F.SilkS")
		)
		(fp_rect
			(start -0.508 0.9398)
			(end 0.508 -0.9398)
			(stroke
				(width 0)
				(type default)
			)
			(fill no)
			(layer "F.CrtYd")
		)
		(fp_rect
			(start -0.508 0.9398)
			(end 0.508 -0.9398)
			(stroke
				(width 0)
				(type default)
			)
			(fill no)
			(layer "F.Fab")
		)
		(pad "1" smd custom
			(at 0 -0.4445 90)
			(size 0.1397 0.1397)
			(layers "F.Cu" "F.Mask" "F.Paste")
			(net "VDD_DIFF_3")
			(options
				(clearance outline)
				(anchor circle)
			)
			(primitives
				(gr_poly
					(pts
						(arc
							(start -0.1778 -0.2794)
							(mid -0.249642 -0.249642)
							(end -0.2794 -0.1778)
						)
						(arc
							(start -0.2794 0.1778)
							(mid -0.249642 0.249642)
							(end -0.1778 0.2794)
						)
						(arc
							(start 0.1778 0.2794)
							(mid 0.249642 0.249642)
							(end 0.2794 0.1778)
						)
						(arc
							(start 0.2794 -0.1778)
							(mid 0.249642 -0.249642)
							(end 0.1778 -0.2794)
						)
					)
					(width 0)
					(fill yes)
				)
			)
		)
		(pad "2" smd custom
			(at 0 0.4445 90)
			(size 0.1397 0.1397)
			(layers "F.Cu" "F.Mask" "F.Paste")
			(net "CLK_BUF_EU3_100M_133M#")
			(options
				(clearance outline)
				(anchor circle)
			)
			(primitives
				(gr_poly
					(pts
						(arc
							(start -0.1778 -0.2794)
							(mid -0.249642 -0.249642)
							(end -0.2794 -0.1778)
						)
						(arc
							(start -0.2794 0.1778)
							(mid -0.249642 0.249642)
							(end -0.1778 0.2794)
						)
						(arc
							(start 0.1778 0.2794)
							(mid 0.249642 0.249642)
							(end 0.2794 0.1778)
						)
						(arc
							(start 0.2794 -0.1778)
							(mid 0.249642 -0.249642)
							(end 0.1778 -0.2794)
						)
					)
					(width 0)
					(fill yes)
				)
			)
		)
	)
	(footprint ""
		(layer "F.Cu")
		(at 83.4644 -431.3047 180)
		(property "Reference" "R9959"
			(at 0 0 180)
			(layer "F.SilkS")
			(hide yes)
			(effects
				(font
					(size 1.27 1.27)
				)
			)
		)
		(property "Value" "100R1F-GP"
			(at -3.3274 -1.3335 180)
			(unlocked yes)
			(layer "F.Fab")
			(hide yes)
			(effects
				(font
					(size 1.016 1.016)
					(thickness 0.1524)
				)
			)
		)
		(property "Device Type" "R0201H12"
			(at -3.3274 -2.8575 180)
			(unlocked yes)
			(layer "F.Fab")
			(hide yes)
			(effects
				(font
					(size 1.016 1.016)
					(thickness 0.1524)
				)
			)
		)
		(duplicate_pad_numbers_are_jumpers no)
		(fp_rect
			(start -0.2794 0.6477)
			(end 0.2794 -0.6477)
			(stroke
				(width 0)
				(type default)
			)
			(fill no)
			(layer "F.CrtYd")
		)
		(fp_rect
			(start -0.2794 0.6477)
			(end 0.2794 -0.6477)
			(stroke
				(width 0)
				(type default)
			)
			(fill no)
			(layer "F.Fab")
		)
		(pad "1" smd custom
			(at 0 -0.2794 180)
			(size 0.0762 0.0762)
			(layers "F.Cu" "F.Mask" "F.Paste")
			(net "PE_100M_CLK4_N")
			(options
				(clearance outline)
				(anchor circle)
			)
			(primitives
				(gr_poly
					(pts
						(arc
							(start 0.1524 -0.127)
							(mid 0.137521 -0.162921)
							(end 0.1016 -0.1778)
						)
						(arc
							(start -0.1016 -0.1778)
							(mid -0.137521 -0.162921)
							(end -0.1524 -0.127)
						)
						(arc
							(start -0.1524 0.127)
							(mid -0.137521 0.162921)
							(end -0.1016 0.1778)
						)
						(arc
							(start 0.1016 0.1778)
							(mid 0.137521 0.162921)
							(end 0.1524 0.127)
						)
					)
					(width 0)
					(fill yes)
				)
			)
		)
		(pad "2" smd custom
			(at 0 0.2794 180)
			(size 0.0762 0.0762)
			(layers "F.Cu" "F.Mask" "F.Paste")
			(net "PE_100M_CLK4_P")
			(options
				(clearance outline)
				(anchor circle)
			)
			(primitives
				(gr_poly
					(pts
						(arc
							(start 0.1524 -0.127)
							(mid 0.137521 -0.162921)
							(end 0.1016 -0.1778)
						)
						(arc
							(start -0.1016 -0.1778)
							(mid -0.137521 -0.162921)
							(end -0.1524 -0.127)
						)
						(arc
							(start -0.1524 0.127)
							(mid -0.137521 0.162921)
							(end -0.1016 0.1778)
						)
						(arc
							(start 0.1016 0.1778)
							(mid 0.137521 0.162921)
							(end 0.1524 0.127)
						)
					)
					(width 0)
					(fill yes)
				)
			)
		)
	)
	(footprint ""
		(layer "F.Cu")
		(at 94.488 -93.853)
		(property "Reference" "C8876"
			(at 0 0 0)
			(layer "F.SilkS")
			(hide yes)
			(effects
				(font
					(size 1.27 1.27)
				)
			)
		)
		(property "Value" "SCD1U16V2KX-3GP"
			(at 1.1811 -2.7051 0)
			(unlocked yes)
			(layer "F.Fab")
			(hide yes)
			(effects
				(font
					(size 1.016 1.016)
					(thickness 0.1524)
				)
			)
		)
		(property "Device Type" "C402H22"
			(at 1.1811 -4.2291 0)
			(unlocked yes)
			(layer "F.Fab")
			(hide yes)
			(effects
				(font
					(size 1.016 1.016)
					(thickness 0.1524)
				)
			)
		)
		(duplicate_pad_numbers_are_jumpers no)
		(fp_rect
			(start -0.4318 0.9525)
			(end 0.4318 -0.9525)
			(stroke
				(width 0)
				(type default)
			)
			(fill no)
			(layer "F.CrtYd")
		)
		(fp_rect
			(start -0.4318 0.9525)
			(end 0.4318 -0.9525)
			(stroke
				(width 0)
				(type default)
			)
			(fill no)
			(layer "F.Fab")
		)
		(pad "1" smd custom
			(at 0 -0.4445)
			(size 0.1524 0.1524)
			(layers "F.Cu" "F.Mask" "F.Paste")
			(net "VDD_IO_4")
			(options
				(clearance outline)
				(anchor circle)
			)
			(primitives
				(gr_poly
					(pts
						(arc
							(start 0.3048 -0.2032)
							(mid 0.275042 -0.275042)
							(end 0.2032 -0.3048)
						)
						(arc
							(start -0.2032 -0.3048)
							(mid -0.275042 -0.275042)
							(end -0.3048 -0.2032)
						)
						(arc
							(start -0.3048 0.2032)
							(mid -0.275042 0.275042)
							(end -0.2032 0.3048)
						)
						(arc
							(start 0.2032 0.3048)
							(mid 0.275042 0.275042)
							(end 0.3048 0.2032)
						)
					)
					(width 0)
					(fill yes)
				)
			)
		)
		(pad "2" smd custom
			(at 0 0.4445)
			(size 0.1524 0.1524)
			(layers "F.Cu" "F.Mask" "F.Paste")
			(net "GND")
			(options
				(clearance outline)
				(anchor circle)
			)
			(primitives
				(gr_poly
					(pts
						(arc
							(start 0.3048 -0.2032)
							(mid 0.275042 -0.275042)
							(end 0.2032 -0.3048)
						)
						(arc
							(start -0.2032 -0.3048)
							(mid -0.275042 -0.275042)
							(end -0.3048 -0.2032)
						)
						(arc
							(start -0.3048 0.2032)
							(mid -0.275042 0.275042)
							(end -0.2032 0.3048)
						)
						(arc
							(start 0.2032 0.3048)
							(mid 0.275042 0.275042)
							(end 0.3048 0.2032)
						)
					)
					(width 0)
					(fill yes)
				)
			)
		)
	)
)
